(kicad_pcb
	(version 20260206)
	(generator "pcbnew")
	(generator_version "10.0")
	(general
		(thickness 1.6)
		(legacy_teardrops no)
	)
	(paper "A4")
	(title_block
		(title "Wiwynn_Tioga_Pass_MB.brd")
		(comment 1 "Tioga Pass / footprints 971-976 of 4770")
	)
	(layers
		(0 "F.Cu" signal "TOP")
		(4 "In1.Cu" signal "L2GND")
		(6 "In2.Cu" signal "L3")
		(8 "In3.Cu" signal "L4GND")
		(10 "In4.Cu" signal "L5")
		(12 "In5.Cu" signal "L6GND")
		(14 "In6.Cu" signal "L7VCC")
		(16 "In7.Cu" signal "L8VCC")
		(18 "In8.Cu" signal "L9GND")
		(20 "In9.Cu" signal "L10")
		(22 "In10.Cu" signal "L11GND")
		(24 "In11.Cu" signal "L12")
		(26 "In12.Cu" signal "L13GND")
		(2 "B.Cu" signal "BOTTOM")
		(9 "F.Adhes" user "F.Adhesive")
		(11 "B.Adhes" user "B.Adhesive")
		(13 "F.Paste" user "Package Geometry/Pastemask Top")
		(15 "B.Paste" user "Package Geometry/Pastemask Bottom")
		(5 "F.SilkS" user "Ref Des/Silkscreen Top")
		(7 "B.SilkS" user "Ref Des/Silkscreen Bottom")
		(1 "F.Mask" user "Board Geometry/Soldermask Top")
		(3 "B.Mask" user "Board Geometry/Soldermask Bottom")
		(17 "Dwgs.User" user "User.Drawings")
		(19 "Cmts.User" user "User.Comments")
		(21 "Eco1.User" user "User.Eco1")
		(23 "Eco2.User" user "User.Eco2")
		(25 "Edge.Cuts" user "Board Geometry/Outline")
		(27 "Margin" user)
		(31 "F.CrtYd" user "Package Geometry/Place Bound Top")
		(29 "B.CrtYd" user "Package Geometry/Place Bound Bottom")
		(35 "F.Fab" user "Ref Des/Assembly Top")
		(33 "B.Fab" user "Ref Des/Assembly Bottom")
	)
	(footprint ""
		(layer "F.Cu")
		(at 441.119006 -43.568874 180)
		(property "Reference" "R25W31"
			(at 0 0 180)
			(layer "F.SilkS")
			(hide yes)
			(effects
				(font
					(size 1.27 1.27)
				)
			)
		)
		(property "Value" "*"
			(at 0.064008 -4.108196 180)
			(unlocked yes)
			(layer "F.Fab")
			(hide yes)
			(effects
				(font
					(size 1.27 1.016)
					(thickness 0.1524)
				)
			)
		)
		(property "Device Type" "120R2F-GP_RCL_GP-120R2F-GP,64.A"
			(at 0.064008 -5.632196 180)
			(unlocked yes)
			(layer "F.Fab")
			(hide yes)
			(effects
				(font
					(size 1.27 1.016)
					(thickness 0.1524)
				)
			)
		)
		(duplicate_pad_numbers_are_jumpers no)
		(fp_line
			(start 0.508 -0.9398)
			(end -0.508 -0.9398)
			(stroke
				(width 0.1524)
				(type default)
			)
			(layer "F.SilkS")
		)
		(fp_line
			(start -0.508 -0.9398)
			(end -0.508 0.9398)
			(stroke
				(width 0.1524)
				(type default)
			)
			(layer "F.SilkS")
		)
		(fp_rect
			(start -0.508 0.9398)
			(end 0.508 -0.9398)
			(stroke
				(width 0)
				(type default)
			)
			(fill no)
			(layer "F.CrtYd")
		)
		(fp_rect
			(start -0.508 0.9398)
			(end 0.508 -0.9398)
			(stroke
				(width 0)
				(type default)
			)
			(fill no)
			(layer "F.Fab")
		)
		(pad "1" smd custom
			(at 0 -0.4445 180)
			(size 0.1397 0.1397)
			(layers "F.Cu" "F.Mask" "F.Paste")
			(net "BMC_M_CS_N")
			(options
				(clearance outline)
				(anchor circle)
			)
			(primitives
				(gr_poly
					(pts
						(arc
							(start -0.1778 -0.2794)
							(mid -0.249642 -0.249642)
							(end -0.2794 -0.1778)
						)
						(arc
							(start -0.2794 0.1778)
							(mid -0.249642 0.249642)
							(end -0.1778 0.2794)
						)
						(arc
							(start 0.1778 0.2794)
							(mid 0.249642 0.249642)
							(end 0.2794 0.1778)
						)
						(arc
							(start 0.2794 -0.1778)
							(mid 0.249642 -0.249642)
							(end 0.1778 -0.2794)
						)
					)
					(width 0)
					(fill yes)
				)
			)
		)
		(pad "2" smd custom
			(at 0 0.4445 180)
			(size 0.1397 0.1397)
			(layers "F.Cu" "F.Mask" "F.Paste")
			(net "P1V2_AUX_BMC")
			(options
				(clearance outline)
				(anchor circle)
			)
			(primitives
				(gr_poly
					(pts
						(arc
							(start -0.1778 -0.2794)
							(mid -0.249642 -0.249642)
							(end -0.2794 -0.1778)
						)
						(arc
							(start -0.2794 0.1778)
							(mid -0.249642 0.249642)
							(end -0.1778 0.2794)
						)
						(arc
							(start 0.1778 0.2794)
							(mid 0.249642 0.249642)
							(end 0.2794 0.1778)
						)
						(arc
							(start 0.2794 -0.1778)
							(mid 0.249642 -0.249642)
							(end 0.1778 -0.2794)
						)
					)
					(width 0)
					(fill yes)
				)
			)
		)
	)
	(footprint ""
		(layer "F.Cu")
		(at 412.1277 -90.0938 180)
		(property "Reference" "R8E5"
			(at 0 0 180)
			(layer "F.SilkS")
			(hide yes)
			(effects
				(font
					(size 1.27 1.27)
				)
			)
		)
		(property "Value" ""
			(at 0 0 180)
			(layer "F.Fab")
			(effects
				(font
					(size 1.27 1.27)
				)
			)
		)
		(duplicate_pad_numbers_are_jumpers no)
		(fp_poly
			(pts
				(xy -0.2794 -0.1016) (xy 0.2794 -0.1016) (xy 0.2794 0.9906) (xy -0.2794 0.9906)
			)
			(stroke
				(width 0)
				(type default)
			)
			(fill no)
			(layer "F.CrtYd")
		)
		(fp_line
			(start 0.2794 0.9906)
			(end 0.2794 -0.1016)
			(stroke
				(width 0.1)
				(type default)
			)
			(layer "F.Fab")
		)
		(fp_line
			(start 0.2794 -0.1016)
			(end -0.2794 -0.1016)
			(stroke
				(width 0.1)
				(type default)
			)
			(layer "F.Fab")
		)
		(fp_line
			(start -0.2794 0.9906)
			(end 0.2794 0.9906)
			(stroke
				(width 0.1)
				(type default)
			)
			(layer "F.Fab")
		)
		(fp_line
			(start -0.2794 -0.1016)
			(end -0.2794 0.9906)
			(stroke
				(width 0.1)
				(type default)
			)
			(layer "F.Fab")
		)
		(pad "1" smd rect
			(at 0 0 180)
			(size 0.508 0.508)
			(layers "F.Cu" "F.Mask" "F.Paste")
			(net "FM_CTNR_PS_ON_R")
		)
		(pad "2" smd rect
			(at 0 0.889 180)
			(size 0.508 0.508)
			(layers "F.Cu" "F.Mask" "F.Paste")
			(net "FM_CTNR_PS_ON")
		)
		(zone
			(layer "F.Cu")
			(hatch none 0.5)
			(connect_pads
				(clearance 0)
			)
			(min_thickness 0.25)
			(keepout
				(tracks not_allowed)
				(vias allowed)
				(pads allowed)
				(copperpour not_allowed)
				(footprints allowed)
			)
			(placement
				(enabled no)
				(sheetname "")
			)
			(fill
				(thermal_gap 0.5)
				(thermal_bridge_width 0.5)
				(island_removal_mode 0)
			)
			(polygon
				(pts
					(xy 412.3817 -90.7288) (xy 411.8737 -90.7288) (xy 411.8737 -90.3478) (xy 412.3817 -90.3478)
				)
			)
		)
		(zone
			(layer "F.Cu")
			(hatch none 0.5)
			(connect_pads
				(clearance 0)
			)
			(min_thickness 0.25)
			(keepout
				(tracks allowed)
				(vias not_allowed)
				(pads allowed)
				(copperpour not_allowed)
				(footprints allowed)
			)
			(placement
				(enabled no)
				(sheetname "")
			)
			(fill
				(thermal_gap 0.5)
				(thermal_bridge_width 0.5)
				(island_removal_mode 0)
			)
			(polygon
				(pts
					(xy 412.3817 -90.3478) (xy 411.8737 -90.3478) (xy 411.8737 -90.7288) (xy 412.3817 -90.7288)
				)
			)
		)
	)
	(footprint ""
		(layer "F.Cu")
		(at 264.453624 -68.641214 -90)
		(property "Reference" "C5D55"
			(at 0 0 270)
			(layer "F.SilkS")
			(hide yes)
			(effects
				(font
					(size 1.27 1.27)
				)
			)
		)
		(property "Value" ""
			(at 0 0 270)
			(layer "F.Fab")
			(effects
				(font
					(size 1.27 1.27)
				)
			)
		)
		(duplicate_pad_numbers_are_jumpers no)
		(fp_poly
			(pts
				(xy -0.4953 -0.2032) (xy 0.4953 -0.2032) (xy 0.4953 1.6002) (xy -0.4953 1.6002)
			)
			(stroke
				(width 0)
				(type default)
			)
			(fill no)
			(layer "F.CrtYd")
		)
		(fp_line
			(start -0.4953 1.6002)
			(end -0.4953 -0.2032)
			(stroke
				(width 0.1)
				(type default)
			)
			(layer "F.Fab")
		)
		(fp_line
			(start 0.4953 1.6002)
			(end -0.4953 1.6002)
			(stroke
				(width 0.1)
				(type default)
			)
			(layer "F.Fab")
		)
		(fp_line
			(start -0.4953 -0.2032)
			(end 0.4953 -0.2032)
			(stroke
				(width 0.1)
				(type default)
			)
			(layer "F.Fab")
		)
		(fp_line
			(start 0.4953 -0.2032)
			(end 0.4953 1.6002)
			(stroke
				(width 0.1)
				(type default)
			)
			(layer "F.Fab")
		)
		(pad "1" smd rect
			(at 0 0 270)
			(size 0.762 0.889)
			(layers "F.Cu" "F.Mask" "F.Paste")
			(net "PVDDQ_ABC")
		)
		(pad "2" smd rect
			(at 0 1.397 270)
			(size 0.762 0.889)
			(layers "F.Cu" "F.Mask" "F.Paste")
			(net "GND")
		)
		(zone
			(layer "F.Cu")
			(hatch none 0.5)
			(connect_pads
				(clearance 0)
			)
			(min_thickness 0.25)
			(keepout
				(tracks not_allowed)
				(vias allowed)
				(pads allowed)
				(copperpour not_allowed)
				(footprints allowed)
			)
			(placement
				(enabled no)
				(sheetname "")
			)
			(fill
				(thermal_gap 0.5)
				(thermal_bridge_width 0.5)
				(island_removal_mode 0)
			)
			(polygon
				(pts
					(xy 264.009124 -69.022214) (xy 264.009124 -68.260214) (xy 263.501124 -68.260214) (xy 263.501124 -69.022214)
				)
			)
		)
	)
	(footprint ""
		(layer "F.Cu")
		(at 278.3332 -79.6036 180)
		(property "Reference" "C6D3"
			(at 0 0 180)
			(layer "F.SilkS")
			(hide yes)
			(effects
				(font
					(size 1.27 1.27)
				)
			)
		)
		(property "Value" ""
			(at 0 0 180)
			(layer "F.Fab")
			(effects
				(font
					(size 1.27 1.27)
				)
			)
		)
		(duplicate_pad_numbers_are_jumpers no)
		(fp_poly
			(pts
				(xy -0.4953 -0.2032) (xy 0.4953 -0.2032) (xy 0.4953 1.6002) (xy -0.4953 1.6002)
			)
			(stroke
				(width 0)
				(type default)
			)
			(fill no)
			(layer "F.CrtYd")
		)
		(fp_line
			(start 0.4953 1.6002)
			(end -0.4953 1.6002)
			(stroke
				(width 0.1)
				(type default)
			)
			(layer "F.Fab")
		)
		(fp_line
			(start 0.4953 -0.2032)
			(end 0.4953 1.6002)
			(stroke
				(width 0.1)
				(type default)
			)
			(layer "F.Fab")
		)
		(fp_line
			(start -0.4953 1.6002)
			(end -0.4953 -0.2032)
			(stroke
				(width 0.1)
				(type default)
			)
			(layer "F.Fab")
		)
		(fp_line
			(start -0.4953 -0.2032)
			(end 0.4953 -0.2032)
			(stroke
				(width 0.1)
				(type default)
			)
			(layer "F.Fab")
		)
		(pad "1" smd rect
			(at 0 0 180)
			(size 0.762 0.889)
			(layers "F.Cu" "F.Mask" "F.Paste")
			(net "PVCCIO_CPU0")
		)
		(pad "2" smd rect
			(at 0 1.397 180)
			(size 0.762 0.889)
			(layers "F.Cu" "F.Mask" "F.Paste")
			(net "GND")
		)
		(zone
			(layer "F.Cu")
			(hatch none 0.5)
			(connect_pads
				(clearance 0)
			)
			(min_thickness 0.25)
			(keepout
				(tracks not_allowed)
				(vias allowed)
				(pads allowed)
				(copperpour not_allowed)
				(footprints allowed)
			)
			(placement
				(enabled no)
				(sheetname "")
			)
			(fill
				(thermal_gap 0.5)
				(thermal_bridge_width 0.5)
				(island_removal_mode 0)
			)
			(polygon
				(pts
					(xy 278.7142 -80.0481) (xy 277.9522 -80.0481) (xy 277.9522 -80.5561) (xy 278.7142 -80.5561)
				)
			)
		)
	)
	(footprint ""
		(layer "F.Cu")
		(at 322.7324 -34.163 -90)
		(property "Reference" "R6F5"
			(at 0 0 270)
			(layer "F.SilkS")
			(hide yes)
			(effects
				(font
					(size 1.27 1.27)
				)
			)
		)
		(property "Value" ""
			(at 0 0 270)
			(layer "F.Fab")
			(effects
				(font
					(size 1.27 1.27)
				)
			)
		)
		(duplicate_pad_numbers_are_jumpers no)
		(fp_poly
			(pts
				(xy -0.2794 -0.1016) (xy 0.2794 -0.1016) (xy 0.2794 0.9906) (xy -0.2794 0.9906)
			)
			(stroke
				(width 0)
				(type default)
			)
			(fill no)
			(layer "F.CrtYd")
		)
		(fp_line
			(start -0.2794 0.9906)
			(end 0.2794 0.9906)
			(stroke
				(width 0.1)
				(type default)
			)
			(layer "F.Fab")
		)
		(fp_line
			(start 0.2794 0.9906)
			(end 0.2794 -0.1016)
			(stroke
				(width 0.1)
				(type default)
			)
			(layer "F.Fab")
		)
		(fp_line
			(start -0.2794 -0.1016)
			(end -0.2794 0.9906)
			(stroke
				(width 0.1)
				(type default)
			)
			(layer "F.Fab")
		)
		(fp_line
			(start 0.2794 -0.1016)
			(end -0.2794 -0.1016)
			(stroke
				(width 0.1)
				(type default)
			)
			(layer "F.Fab")
		)
		(pad "1" smd rect
			(at 0 0 270)
			(size 0.508 0.508)
			(layers "F.Cu" "F.Mask" "F.Paste")
			(net "FM_ADR_COMPLETE_CPU1_N")
		)
		(pad "2" smd rect
			(at 0 0.889 270)
			(size 0.508 0.508)
			(layers "F.Cu" "F.Mask" "F.Paste")
			(net "FM_ADR_COMPLETE_GHJ_N")
		)
		(zone
			(layer "F.Cu")
			(hatch none 0.5)
			(connect_pads
				(clearance 0)
			)
			(min_thickness 0.25)
			(keepout
				(tracks not_allowed)
				(vias allowed)
				(pads allowed)
				(copperpour not_allowed)
				(footprints allowed)
			)
			(placement
				(enabled no)
				(sheetname "")
			)
			(fill
				(thermal_gap 0.5)
				(thermal_bridge_width 0.5)
				(island_removal_mode 0)
			)
			(polygon
				(pts
					(xy 322.0974 -34.417) (xy 322.0974 -33.909) (xy 322.4784 -33.909) (xy 322.4784 -34.417)
				)
			)
		)
		(zone
			(layer "F.Cu")
			(hatch none 0.5)
			(connect_pads
				(clearance 0)
			)
			(min_thickness 0.25)
			(keepout
				(tracks allowed)
				(vias not_allowed)
				(pads allowed)
				(copperpour not_allowed)
				(footprints allowed)
			)
			(placement
				(enabled no)
				(sheetname "")
			)
			(fill
				(thermal_gap 0.5)
				(thermal_bridge_width 0.5)
				(island_removal_mode 0)
			)
			(polygon
				(pts
					(xy 322.4784 -34.417) (xy 322.4784 -33.909) (xy 322.0974 -33.909) (xy 322.0974 -34.417)
				)
			)
		)
	)
	(footprint ""
		(layer "F.Cu")
		(at 18.4912 -26.67 90)
		(property "Reference" "J1F3"
			(at 1.91643 14.8463 0)
			(unlocked yes)
			(layer "B.SilkS")
			(effects
				(font
					(size 0.7874 0.5842)
					(thickness 0.1524)
				)
				(justify left mirror)
			)
		)
		(property "Value" ""
			(at 0 0 90)
			(layer "F.Fab")
			(effects
				(font
					(size 1.27 1.27)
				)
			)
		)
		(duplicate_pad_numbers_are_jumpers no)
		(fp_line
			(start 2.169922 -1.599946)
			(end 2.169922 10.349992)
			(stroke
				(width 0.1524)
				(type default)
			)
			(layer "F.SilkS")
		)
		(fp_line
			(start -1.230122 -1.599946)
			(end 2.169922 -1.599946)
			(stroke
				(width 0.1524)
				(type default)
			)
			(layer "F.SilkS")
		)
		(fp_line
			(start 2.169922 10.349992)
			(end -1.230122 10.349992)
			(stroke
				(width 0.1524)
				(type default)
			)
			(layer "F.SilkS")
		)
		(fp_line
			(start -1.230122 10.349992)
			(end -1.230122 -1.599946)
			(stroke
				(width 0.1524)
				(type default)
			)
			(layer "F.SilkS")
		)
		(fp_poly
			(pts
				(xy -2.709418 -1.590802) (xy -2.709418 -0.574802) (xy -1.439418 -1.082802)
			)
			(stroke
				(width 0)
				(type default)
			)
			(fill yes)
			(layer "F.SilkS")
		)
		(fp_poly
			(pts
				(xy -3.141218 -0.549402) (xy -3.141218 0.466598) (xy -1.871218 -0.041402)
			)
			(stroke
				(width 0)
				(type default)
			)
			(fill yes)
			(layer "B.SilkS")
		)
		(fp_poly
			(pts
				(xy -1.230122 -1.599946) (xy -1.230122 10.349992) (xy 2.169922 10.349992) (xy 2.169922 -1.599946)
			)
			(stroke
				(width 0)
				(type default)
			)
			(fill no)
			(layer "F.CrtYd")
		)
		(fp_poly
			(pts
				(xy -3.141218 -0.549402) (xy -3.141218 0.466598) (xy -1.871218 -0.041402)
			)
			(stroke
				(width 0)
				(type default)
			)
			(fill yes)
			(layer "B.Fab")
		)
		(fp_line
			(start 2.169922 -1.599946)
			(end 2.169922 10.349992)
			(stroke
				(width 0.1)
				(type default)
			)
			(layer "F.Fab")
		)
		(fp_line
			(start -1.230122 -1.599946)
			(end 2.169922 -1.599946)
			(stroke
				(width 0.1)
				(type default)
			)
			(layer "F.Fab")
		)
		(fp_line
			(start 2.169922 10.349992)
			(end -1.230122 10.349992)
			(stroke
				(width 0.1)
				(type default)
			)
			(layer "F.Fab")
		)
		(fp_line
			(start -1.230122 10.349992)
			(end -1.230122 -1.599946)
			(stroke
				(width 0.1)
				(type default)
			)
			(layer "F.Fab")
		)
		(fp_text user "8"
			(at 2.413 9.22147 90)
			(unlocked yes)
			(layer "F.SilkS")
			(effects
				(font
					(size 0.7874 0.5842)
					(thickness 0.1524)
				)
				(justify left)
			)
		)
		(fp_text user "8"
			(at -1.896618 8.83285 90)
			(unlocked yes)
			(layer "B.SilkS")
			(effects
				(font
					(size 0.7874 0.5842)
					(thickness 0.1524)
				)
				(justify left mirror)
			)
		)
		(fp_text user "8"
			(at -1.896618 8.83285 90)
			(unlocked yes)
			(layer "B.Fab")
			(effects
				(font
					(size 0.7874 0.5842)
					(thickness 0.1524)
				)
				(justify left mirror)
			)
		)
		(fp_text user "8"
			(at -2.03327 -0.381 0)
			(unlocked yes)
			(layer "F.Fab")
			(effects
				(font
					(size 0.7874 0.5842)
					(thickness 0.1524)
				)
				(justify left)
			)
		)
		(pad "1" thru_hole rect
			(at 0 0 90)
			(size 0.9906 0.9906)
			(drill 0.6096)
			(layers "*.Cu" "*.Mask")
			(remove_unused_layers no)
			(net "P3V3_STBY")
			(clearance 0.127)
			(thermal_gap 0.127)
			(padstack
				(mode front_inner_back)
				(layer "Inner"
					(shape circle)
					(size 0.9906 0.9906)
					(clearance 0.127)
				)
				(layer "B.Cu"
					(shape rect)
					(size 0.9906 0.9906)
					(clearance 0.127)
				)
			)
		)
		(pad "2" thru_hole circle
			(at 0 1.249934 90)
			(size 0.9906 0.9906)
			(drill 0.6096)
			(layers "*.Cu" "*.Mask")
			(remove_unused_layers no)
			(net "FM_MP_PS_REDUNDANT_LOST_N")
			(clearance 0.127)
			(thermal_gap 0.127)
		)
		(pad "3" thru_hole circle
			(at 0 2.500122 90)
			(size 0.9906 0.9906)
			(drill 0.6096)
			(layers "*.Cu" "*.Mask")
			(remove_unused_layers no)
			(net "FM_MP_PS_FAIL_N")
			(clearance 0.127)
			(thermal_gap 0.127)
		)
		(pad "4" thru_hole circle
			(at 0 3.750056 90)
			(size 0.9906 0.9906)
			(drill 0.6096)
			(layers "*.Cu" "*.Mask")
			(remove_unused_layers no)
			(net "FM_MATED_IN_N")
			(clearance 0.127)
			(thermal_gap 0.127)
		)
		(pad "5" thru_hole circle
			(at 0 4.99999 90)
			(size 0.9906 0.9906)
			(drill 0.6096)
			(layers "*.Cu" "*.Mask")
			(remove_unused_layers no)
			(net "IRQ_SML1_PMBUS_ALERT_R_N")
			(clearance 0.127)
			(thermal_gap 0.127)
		)
		(pad "6" thru_hole circle
			(at 0 6.249924 90)
			(size 0.9906 0.9906)
			(drill 0.6096)
			(layers "*.Cu" "*.Mask")
			(remove_unused_layers no)
			(net "SMB_BMC_PMBUS_STBY_LVC3_SDA")
			(clearance 0.127)
			(thermal_gap 0.127)
		)
		(pad "7" thru_hole circle
			(at 0 7.500112 90)
			(size 0.9906 0.9906)
			(drill 0.6096)
			(layers "*.Cu" "*.Mask")
			(remove_unused_layers no)
			(net "SMB_BMC_PMBUS_STBY_LVC3_SCL")
			(clearance 0.127)
			(thermal_gap 0.127)
		)
		(pad "8" thru_hole circle
			(at 0 8.750046 90)
			(size 0.9906 0.9906)
			(drill 0.6096)
			(layers "*.Cu" "*.Mask")
			(remove_unused_layers no)
			(net "GND")
			(clearance 0.127)
			(thermal_gap 0.127)
		)
	)
)
